# SCM (Grand Teton) — schematic netlist excerpt (pin names and nets, part order shuffled) for the footprints in the layout excerpt that follows; sources: Cadence DE-HDL packaged netlist, KiCad conversion of 12092022_DA0F0TMDCD0_F0T_Management_Board_D_brd_V3_OCP.brd

R237  Q_RES  33.2 1% CHIP  pkg 0402LF  page 13 : A = FM_DBP_BMC_PRDY_N ; B = FM_DBP_BMC_PRDY_R_N

U36  74HC1G126GW  IC  pkg TSSOP5_0-65_2-05X1-25  page 29
  \1\  = DEBUG_PORT_PRSNT
  \2\  = DEBUG_PORT_UART_RX
  GND  = GND
  \4\  = SPA_SIN_SW_DBG
  \5\  = P3V3_AUX

(kicad_pcb
	(version 20260206)
	(generator "pcbnew")
	(generator_version "10.0")
	(general
		(thickness 1.6)
		(legacy_teardrops no)
	)
	(paper "A4")
	(title_block
		(title "12092022_DA0F0TMDCD0_F0T_Management_Board_D_brd_V3_OCP.brd")
		(comment 1 "Grand Teton / footprints 1151-1152 of 1440")
	)
	(layers
		(0 "F.Cu" signal "TOP")
		(4 "In1.Cu" signal "GND")
		(6 "In2.Cu" signal "IN1")
		(8 "In3.Cu" signal "GND1")
		(10 "In4.Cu" signal "IN2")
		(12 "In5.Cu" signal "VCC")
		(14 "In6.Cu" signal "VCC1")
		(16 "In7.Cu" signal "IN3")
		(18 "In8.Cu" signal "GND2")
		(20 "In9.Cu" signal "IN4")
		(22 "In10.Cu" signal "GND3")
		(2 "B.Cu" signal "BOTTOM")
		(9 "F.Adhes" user "F.Adhesive")
		(11 "B.Adhes" user "B.Adhesive")
		(13 "F.Paste" user "Package Geometry/Pastemask Top")
		(15 "B.Paste" user "Package Geometry/Pastemask Bottom")
		(5 "F.SilkS" user "Ref Des/Silkscreen Top")
		(7 "B.SilkS" user "Ref Des/Silkscreen Bottom")
		(1 "F.Mask" user "Board Geometry/Soldermask Top")
		(3 "B.Mask" user "Board Geometry/Soldermask Bottom")
		(17 "Dwgs.User" user "User.Drawings")
		(19 "Cmts.User" user "User.Comments")
		(21 "Eco1.User" user "User.Eco1")
		(23 "Eco2.User" user "User.Eco2")
		(25 "Edge.Cuts" user "Board Geometry/Outline")
		(27 "Margin" user)
		(31 "F.CrtYd" user "Package Geometry/Place Bound Top")
		(29 "B.CrtYd" user "Package Geometry/Place Bound Bottom")
		(35 "F.Fab" user "Ref Des/Assembly Top")
		(33 "B.Fab" user "Ref Des/Assembly Bottom")
	)
	(footprint ""
		(layer "B.Cu")
		(at 62.23 -21.082 -90)
		(property "Reference" "U36"
			(at 0.0254 -1.87833 270)
			(unlocked yes)
			(layer "B.SilkS")
			(effects
				(font
					(size 0.7874 0.5842)
					(thickness 0.1524)
				)
				(justify left mirror)
			)
		)
		(property "Value" ""
			(at 0 0 90)
			(layer "B.Fab")
			(effects
				(font
					(size 1.27 1.27)
				)
				(justify mirror)
			)
		)
		(duplicate_pad_numbers_are_jumpers no)
		(fp_line
			(start -1.3462 1.1938)
			(end -1.3462 -1.1938)
			(stroke
				(width 0.1524)
				(type default)
			)
			(layer "B.SilkS")
		)
		(fp_line
			(start 1.3462 1.1938)
			(end -1.3462 1.1938)
			(stroke
				(width 0.1524)
				(type default)
			)
			(layer "B.SilkS")
		)
		(fp_line
			(start -1.3462 -1.1938)
			(end 1.3462 -1.1938)
			(stroke
				(width 0.1524)
				(type default)
			)
			(layer "B.SilkS")
		)
		(fp_line
			(start 1.3462 -1.1938)
			(end 1.3462 1.1684)
			(stroke
				(width 0.1524)
				(type default)
			)
			(layer "B.SilkS")
		)
		(fp_poly
			(pts
				(xy 1.447038 -0.760476) (xy 2.052066 -0.457962) (xy 2.052066 -1.06299)
			)
			(stroke
				(width 0)
				(type default)
			)
			(fill yes)
			(layer "B.SilkS")
		)
		(fp_line
			(start -0.674878 1.124966)
			(end -0.674878 -1.124966)
			(stroke
				(width 0.1)
				(type default)
			)
			(layer "B.Fab")
		)
		(fp_line
			(start 0.674878 1.124966)
			(end -0.674878 1.124966)
			(stroke
				(width 0.1)
				(type default)
			)
			(layer "B.Fab")
		)
		(fp_line
			(start -0.674878 -1.124966)
			(end 0.674878 -1.124966)
			(stroke
				(width 0.1)
				(type default)
			)
			(layer "B.Fab")
		)
		(fp_line
			(start 0.674878 -1.124966)
			(end 0.674878 1.124966)
			(stroke
				(width 0.1)
				(type default)
			)
			(layer "B.Fab")
		)
		(fp_poly
			(pts
				(xy 1.447038 -0.760476) (xy 2.052066 -0.457962) (xy 2.052066 -1.06299)
			)
			(stroke
				(width 0)
				(type default)
			)
			(fill yes)
			(layer "B.Fab")
		)
		(pad "1" smd rect
			(at 0.899922 -0.750062 90)
			(size 0.6096 0.6096)
			(layers "B.Cu" "B.Mask" "B.Paste")
			(net "DEBUG_PORT_PRSNT")
		)
		(pad "2" smd rect
			(at 0.899922 0)
			(size 0.4064 0.6096)
			(layers "B.Cu" "B.Mask" "B.Paste")
			(net "DEBUG_PORT_UART_RX")
		)
		(pad "3" smd rect
			(at 0.899922 0.750062 90)
			(size 0.6096 0.6096)
			(layers "B.Cu" "B.Mask" "B.Paste")
			(net "GND")
		)
		(pad "4" smd rect
			(at -0.899922 0.750062 90)
			(size 0.6096 0.6096)
			(layers "B.Cu" "B.Mask" "B.Paste")
			(net "SPA_SIN_SW_DBG")
		)
		(pad "5" smd rect
			(at -0.899922 -0.750062 90)
			(size 0.6096 0.6096)
			(layers "B.Cu" "B.Mask" "B.Paste")
			(net "P3V3_AUX")
		)
	)
	(footprint ""
		(layer "B.Cu")
		(at 61.423804 -34.637726 -90)
		(property "Reference" "R237"
			(at 0 0 90)
			(layer "B.SilkS")
			(hide yes)
			(effects
				(font
					(size 1.27 1.27)
				)
				(justify mirror)
			)
		)
		(property "Value" ""
			(at 0 0 90)
			(layer "B.Fab")
			(effects
				(font
					(size 1.27 1.27)
				)
				(justify mirror)
			)
		)
		(duplicate_pad_numbers_are_jumpers no)
		(fp_line
			(start -0.7874 0.4064)
			(end 0.7874 0.4064)
			(stroke
				(width 0.1524)
				(type default)
			)
			(layer "B.SilkS")
		)
		(fp_line
			(start 0.7874 0.4064)
			(end 0.7874 -0.4064)
			(stroke
				(width 0.1524)
				(type default)
			)
			(layer "B.SilkS")
		)
		(fp_line
			(start -0.7874 -0.4064)
			(end -0.7874 0.4064)
			(stroke
				(width 0.1524)
				(type default)
			)
			(layer "B.SilkS")
		)
		(fp_line
			(start 0.7874 -0.4064)
			(end -0.7874 -0.4064)
			(stroke
				(width 0.1524)
				(type default)
			)
			(layer "B.SilkS")
		)
		(fp_line
			(start -0.67945 0.3048)
			(end -0.120396 0.3048)
			(stroke
				(width 0.1)
				(type default)
			)
			(layer "B.Fab")
		)
		(fp_line
			(start -0.120396 0.3048)
			(end -0.120396 0.2794)
			(stroke
				(width 0.1)
				(type default)
			)
			(layer "B.Fab")
		)
		(fp_line
			(start 0.12065 0.3048)
			(end 0.67945 0.3048)
			(stroke
				(width 0.1)
				(type default)
			)
			(layer "B.Fab")
		)
		(fp_line
			(start 0.67945 0.3048)
			(end 0.67945 -0.305054)
			(stroke
				(width 0.1)
				(type default)
			)
			(layer "B.Fab")
		)
		(fp_line
			(start -0.120396 0.2794)
			(end 0.12065 0.2794)
			(stroke
				(width 0.1)
				(type default)
			)
			(layer "B.Fab")
		)
		(fp_line
			(start 0.12065 0.2794)
			(end 0.12065 0.3048)
			(stroke
				(width 0.1)
				(type default)
			)
			(layer "B.Fab")
		)
		(fp_line
			(start -0.12065 -0.2794)
			(end -0.12065 -0.3048)
			(stroke
				(width 0.1)
				(type default)
			)
			(layer "B.Fab")
		)
		(fp_line
			(start 0.12065 -0.2794)
			(end -0.12065 -0.2794)
			(stroke
				(width 0.1)
				(type default)
			)
			(layer "B.Fab")
		)
		(fp_line
			(start -0.67945 -0.3048)
			(end -0.67945 0.3048)
			(stroke
				(width 0.1)
				(type default)
			)
			(layer "B.Fab")
		)
		(fp_line
			(start -0.12065 -0.3048)
			(end -0.67945 -0.3048)
			(stroke
				(width 0.1)
				(type default)
			)
			(layer "B.Fab")
		)
		(fp_line
			(start 0.12065 -0.305054)
			(end 0.12065 -0.2794)
			(stroke
				(width 0.1)
				(type default)
			)
			(layer "B.Fab")
		)
		(fp_line
			(start 0.67945 -0.305054)
			(end 0.12065 -0.305054)
			(stroke
				(width 0.1)
				(type default)
			)
			(layer "B.Fab")
		)
		(pad "1" smd circle
			(at 0.40005 0 90)
			(size 0 0)
			(layers "B.Cu" "B.Mask" "B.Paste")
			(net "FM_DBP_BMC_PRDY_N")
		)
		(pad "2" smd circle
			(at -0.40005 0 90)
			(size 0 0)
			(layers "B.Cu" "B.Mask" "B.Paste")
			(net "FM_DBP_BMC_PRDY_R_N")
		)
	)
)
